# S9S_MB_2U (Grand Teton) — schematic netlist excerpt (pin names and nets, part order shuffled) for the footprints in the layout excerpt that follows; sources: Cadence DE-HDL packaged netlist, KiCad conversion of 03242023_DA0F0TMBIJ0_F0T_Motherboard_J_brd_V01_OCP.brd

PC1195_P1_3  Q_CAP  1UF 16V 10% X6S  pkg C0402  page 290 : A = SW_P12V_PVCCFA_EHV_FIVRA_CPU1_R ; B = GND
PC1266  Q_CAP  680PF 50V 10% X7R  pkg 0402  page 299 : A = PVPP_HBM_CPU1_FB ; B = SH_PVPP_HBM_CPU1_P

(kicad_pcb
	(version 20260206)
	(generator "pcbnew")
	(generator_version "10.0")
	(general
		(thickness 1.6)
		(legacy_teardrops no)
	)
	(paper "A4")
	(title_block
		(title "03242023_DA0F0TMBIJ0_F0T_Motherboard_J_brd_V01_OCP.brd")
		(comment 1 "Grand Teton / footprints 3652-3653 of 6105")
	)
	(layers
		(0 "F.Cu" signal "TOP")
		(4 "In1.Cu" signal "GND")
		(6 "In2.Cu" signal "IN1")
		(8 "In3.Cu" signal "GND1")
		(10 "In4.Cu" signal "IN2")
		(12 "In5.Cu" signal "GND2")
		(14 "In6.Cu" signal "IN3")
		(16 "In7.Cu" signal "GND3")
		(18 "In8.Cu" signal "VCC")
		(20 "In9.Cu" signal "VCC1")
		(22 "In10.Cu" signal "GND4")
		(24 "In11.Cu" signal "IN4")
		(26 "In12.Cu" signal "GND5")
		(28 "In13.Cu" signal "IN5")
		(30 "In14.Cu" signal "GND6")
		(32 "In15.Cu" signal "IN6")
		(34 "In16.Cu" signal "GND7")
		(2 "B.Cu" signal "BOTTOM")
		(9 "F.Adhes" user "F.Adhesive")
		(11 "B.Adhes" user "B.Adhesive")
		(13 "F.Paste" user "Package Geometry/Pastemask Top")
		(15 "B.Paste" user "Package Geometry/Pastemask Bottom")
		(5 "F.SilkS" user "Ref Des/Silkscreen Top")
		(7 "B.SilkS" user "Ref Des/Silkscreen Bottom")
		(1 "F.Mask" user "Board Geometry/Soldermask Top")
		(3 "B.Mask" user "Board Geometry/Soldermask Bottom")
		(17 "Dwgs.User" user "User.Drawings")
		(19 "Cmts.User" user "User.Comments")
		(21 "Eco1.User" user "User.Eco1")
		(23 "Eco2.User" user "User.Eco2")
		(25 "Edge.Cuts" user "Board Geometry/Outline")
		(27 "Margin" user)
		(31 "F.CrtYd" user "Package Geometry/Place Bound Top")
		(29 "B.CrtYd" user "Package Geometry/Place Bound Bottom")
		(35 "F.Fab" user "Ref Des/Assembly Top")
		(33 "B.Fab" user "Ref Des/Assembly Bottom")
	)
	(footprint ""
		(layer "F.Cu")
		(at 185.346086 -353.650296 -90)
		(property "Reference" "PC1195_P1_3"
			(at 0 0 270)
			(layer "F.SilkS")
			(hide yes)
			(effects
				(font
					(size 1.27 1.27)
				)
			)
		)
		(property "Value" ""
			(at 0 0 270)
			(layer "F.Fab")
			(effects
				(font
					(size 1.27 1.27)
				)
			)
		)
		(duplicate_pad_numbers_are_jumpers no)
		(fp_line
			(start -0.7874 0.4064)
			(end -0.7874 -0.4064)
			(stroke
				(width 0.1524)
				(type default)
			)
			(layer "F.SilkS")
		)
		(fp_line
			(start 0.7874 0.4064)
			(end -0.7874 0.4064)
			(stroke
				(width 0.1524)
				(type default)
			)
			(layer "F.SilkS")
		)
		(fp_line
			(start -0.7874 -0.4064)
			(end 0.7874 -0.4064)
			(stroke
				(width 0.1524)
				(type default)
			)
			(layer "F.SilkS")
		)
		(fp_line
			(start 0.7874 -0.4064)
			(end 0.7874 0.4064)
			(stroke
				(width 0.1524)
				(type default)
			)
			(layer "F.SilkS")
		)
		(fp_line
			(start -0.67945 0.3048)
			(end -0.67945 -0.305054)
			(stroke
				(width 0.1)
				(type default)
			)
			(layer "F.Fab")
		)
		(fp_line
			(start -0.12065 0.3048)
			(end -0.67945 0.3048)
			(stroke
				(width 0.1)
				(type default)
			)
			(layer "F.Fab")
		)
		(fp_line
			(start 0.120396 0.3048)
			(end 0.120396 0.2794)
			(stroke
				(width 0.1)
				(type default)
			)
			(layer "F.Fab")
		)
		(fp_line
			(start 0.67945 0.3048)
			(end 0.120396 0.3048)
			(stroke
				(width 0.1)
				(type default)
			)
			(layer "F.Fab")
		)
		(fp_line
			(start -0.12065 0.2794)
			(end -0.12065 0.3048)
			(stroke
				(width 0.1)
				(type default)
			)
			(layer "F.Fab")
		)
		(fp_line
			(start 0.120396 0.2794)
			(end -0.12065 0.2794)
			(stroke
				(width 0.1)
				(type default)
			)
			(layer "F.Fab")
		)
		(fp_line
			(start -0.12065 -0.2794)
			(end 0.12065 -0.2794)
			(stroke
				(width 0.1)
				(type default)
			)
			(layer "F.Fab")
		)
		(fp_line
			(start 0.12065 -0.2794)
			(end 0.12065 -0.3048)
			(stroke
				(width 0.1)
				(type default)
			)
			(layer "F.Fab")
		)
		(fp_line
			(start 0.12065 -0.3048)
			(end 0.67945 -0.3048)
			(stroke
				(width 0.1)
				(type default)
			)
			(layer "F.Fab")
		)
		(fp_line
			(start 0.67945 -0.3048)
			(end 0.67945 0.3048)
			(stroke
				(width 0.1)
				(type default)
			)
			(layer "F.Fab")
		)
		(fp_line
			(start -0.67945 -0.305054)
			(end -0.12065 -0.305054)
			(stroke
				(width 0.1)
				(type default)
			)
			(layer "F.Fab")
		)
		(fp_line
			(start -0.12065 -0.305054)
			(end -0.12065 -0.2794)
			(stroke
				(width 0.1)
				(type default)
			)
			(layer "F.Fab")
		)
		(pad "1" smd circle
			(at -0.40005 0 270)
			(size 0 0)
			(layers "F.Cu" "F.Mask" "F.Paste")
			(net "SW_P12V_PVCCFA_EHV_FIVRA_CPU1_R")
		)
		(pad "2" smd circle
			(at 0.40005 0 270)
			(size 0 0)
			(layers "F.Cu" "F.Mask" "F.Paste")
			(net "GND")
		)
	)
	(footprint ""
		(layer "F.Cu")
		(at 121.251472 -357.11638 90)
		(property "Reference" "PC1266"
			(at 0 0 90)
			(layer "F.SilkS")
			(hide yes)
			(effects
				(font
					(size 1.27 1.27)
				)
			)
		)
		(property "Value" ""
			(at 0 0 90)
			(layer "F.Fab")
			(effects
				(font
					(size 1.27 1.27)
				)
			)
		)
		(duplicate_pad_numbers_are_jumpers no)
		(fp_line
			(start 0.7874 -0.4064)
			(end 0.7874 0.4064)
			(stroke
				(width 0.1524)
				(type default)
			)
			(layer "F.SilkS")
		)
		(fp_line
			(start -0.7874 -0.4064)
			(end 0.7874 -0.4064)
			(stroke
				(width 0.1524)
				(type default)
			)
			(layer "F.SilkS")
		)
		(fp_line
			(start 0.7874 0.4064)
			(end -0.7874 0.4064)
			(stroke
				(width 0.1524)
				(type default)
			)
			(layer "F.SilkS")
		)
		(fp_line
			(start -0.7874 0.4064)
			(end -0.7874 -0.4064)
			(stroke
				(width 0.1524)
				(type default)
			)
			(layer "F.SilkS")
		)
		(fp_line
			(start -0.12065 -0.305054)
			(end -0.12065 -0.2794)
			(stroke
				(width 0.1)
				(type default)
			)
			(layer "F.Fab")
		)
		(fp_line
			(start -0.67945 -0.305054)
			(end -0.12065 -0.305054)
			(stroke
				(width 0.1)
				(type default)
			)
			(layer "F.Fab")
		)
		(fp_line
			(start 0.67945 -0.3048)
			(end 0.67945 0.3048)
			(stroke
				(width 0.1)
				(type default)
			)
			(layer "F.Fab")
		)
		(fp_line
			(start 0.12065 -0.3048)
			(end 0.67945 -0.3048)
			(stroke
				(width 0.1)
				(type default)
			)
			(layer "F.Fab")
		)
		(fp_line
			(start 0.12065 -0.2794)
			(end 0.12065 -0.3048)
			(stroke
				(width 0.1)
				(type default)
			)
			(layer "F.Fab")
		)
		(fp_line
			(start -0.12065 -0.2794)
			(end 0.12065 -0.2794)
			(stroke
				(width 0.1)
				(type default)
			)
			(layer "F.Fab")
		)
		(fp_line
			(start 0.120396 0.2794)
			(end -0.12065 0.2794)
			(stroke
				(width 0.1)
				(type default)
			)
			(layer "F.Fab")
		)
		(fp_line
			(start -0.12065 0.2794)
			(end -0.12065 0.3048)
			(stroke
				(width 0.1)
				(type default)
			)
			(layer "F.Fab")
		)
		(fp_line
			(start 0.67945 0.3048)
			(end 0.120396 0.3048)
			(stroke
				(width 0.1)
				(type default)
			)
			(layer "F.Fab")
		)
		(fp_line
			(start 0.120396 0.3048)
			(end 0.120396 0.2794)
			(stroke
				(width 0.1)
				(type default)
			)
			(layer "F.Fab")
		)
		(fp_line
			(start -0.12065 0.3048)
			(end -0.67945 0.3048)
			(stroke
				(width 0.1)
				(type default)
			)
			(layer "F.Fab")
		)
		(fp_line
			(start -0.67945 0.3048)
			(end -0.67945 -0.305054)
			(stroke
				(width 0.1)
				(type default)
			)
			(layer "F.Fab")
		)
		(pad "1" smd circle
			(at -0.40005 0 90)
			(size 0 0)
			(layers "F.Cu" "F.Mask" "F.Paste")
			(net "PVPP_HBM_CPU1_FB")
		)
		(pad "2" smd circle
			(at 0.40005 0 90)
			(size 0 0)
			(layers "F.Cu" "F.Mask" "F.Paste")
			(net "SH_PVPP_HBM_CPU1_P")
		)
	)
)
